(kicad_pcb
	(version 20260206)
	(generator "pcbnew")
	(generator_version "10.0")
	(general
		(thickness 1.6)
		(legacy_teardrops no)
	)
	(paper "A4")
	(title_block
		(title "Bryce Canyon_R.DPB_16317-1_OCP.brd")
		(comment 1 "Bryce Canyon / footprint 274 of 2099 (SAS1), pads 294-342 of 342")
	)
	(layers
		(0 "F.Cu" signal "TOP")
		(4 "In1.Cu" signal "L2GND")
		(6 "In2.Cu" signal "L3")
		(8 "In3.Cu" signal "L4VCC")
		(10 "In4.Cu" signal "L5VCC")
		(12 "In5.Cu" signal "L6")
		(14 "In6.Cu" signal "L7GND")
		(2 "B.Cu" signal "BOTTOM")
		(9 "F.Adhes" user "F.Adhesive")
		(11 "B.Adhes" user "B.Adhesive")
		(13 "F.Paste" user "Package Geometry/Pastemask Top")
		(15 "B.Paste" user "Package Geometry/Pastemask Bottom")
		(5 "F.SilkS" user "Ref Des/Silkscreen Top")
		(7 "B.SilkS" user "Ref Des/Silkscreen Bottom")
		(1 "F.Mask" user "Board Geometry/Soldermask Top")
		(3 "B.Mask" user "Board Geometry/Soldermask Bottom")
		(17 "Dwgs.User" user "User.Drawings")
		(19 "Cmts.User" user "User.Comments")
		(21 "Eco1.User" user "User.Eco1")
		(23 "Eco2.User" user "User.Eco2")
		(25 "Edge.Cuts" user "Board Geometry/Outline")
		(27 "Margin" user)
		(31 "F.CrtYd" user "Package Geometry/Place Bound Top")
		(29 "B.CrtYd" user "Package Geometry/Place Bound Bottom")
		(35 "F.Fab" user "Ref Des/Assembly Top")
		(33 "B.Fab" user "Ref Des/Assembly Bottom")
	)
	(footprint ""
		(layer "F.Cu")
		(at 287.83661 -238.694468 -90)
		(property "Reference" "SAS1"
			(at 0 0 270)
			(layer "F.SilkS")
			(hide yes)
			(effects
				(font
					(size 1.27 1.27)
				)
			)
		)
		(property "Value" "AMP-CONN342-10R-2-GP"
			(at 20.955 -16.7386 270)
			(unlocked yes)
			(layer "F.Fab")
			(hide yes)
			(effects
				(font
					(size 1.016 1.016)
					(thickness 0.1524)
				)
			)
		)
		(property "Device Type" "PREFIT-342P-668151H483"
			(at 20.955 -18.2626 270)
			(unlocked yes)
			(layer "F.Fab")
			(hide yes)
			(effects
				(font
					(size 1.016 1.016)
					(thickness 0.1524)
				)
			)
		)
		(duplicate_pad_numbers_are_jumpers no)
		(pad "GND78" thru_hole circle
			(at 39.600124 2.500122 270)
			(size 0.762 0.762)
			(drill 0.359918)
			(layers "*.Cu" "*.Mask")
			(remove_unused_layers no)
			(net "GND")
			(clearance 0.1651)
			(thermal_gap 0.1651)
		)
		(pad "GND79" thru_hole circle
			(at 39.600124 6.100064 270)
			(size 0.762 0.762)
			(drill 0.359918)
			(layers "*.Cu" "*.Mask")
			(remove_unused_layers no)
			(net "GND")
			(clearance 0.1651)
			(thermal_gap 0.1651)
		)
		(pad "GND80" thru_hole circle
			(at 39.600124 9.700006 270)
			(size 0.762 0.762)
			(drill 0.359918)
			(layers "*.Cu" "*.Mask")
			(remove_unused_layers no)
			(net "GND")
			(clearance 0.1651)
			(thermal_gap 0.1651)
		)
		(pad "GND81" thru_hole circle
			(at 41.399968 -0.100076 270)
			(size 0.762 0.762)
			(drill 0.359918)
			(layers "*.Cu" "*.Mask")
			(remove_unused_layers no)
			(net "GND")
			(clearance 0.1651)
			(thermal_gap 0.1651)
		)
		(pad "GND82" thru_hole circle
			(at 41.399968 3.50012 270)
			(size 0.762 0.762)
			(drill 0.359918)
			(layers "*.Cu" "*.Mask")
			(remove_unused_layers no)
			(net "GND")
			(clearance 0.1651)
			(thermal_gap 0.1651)
		)
		(pad "GND83" thru_hole circle
			(at 41.399968 7.100062 270)
			(size 0.762 0.762)
			(drill 0.359918)
			(layers "*.Cu" "*.Mask")
			(remove_unused_layers no)
			(net "GND")
			(clearance 0.1651)
			(thermal_gap 0.1651)
		)
		(pad "GND84" thru_hole circle
			(at 41.399968 10.700004 270)
			(size 0.762 0.762)
			(drill 0.359918)
			(layers "*.Cu" "*.Mask")
			(remove_unused_layers no)
			(net "GND")
			(clearance 0.1651)
			(thermal_gap 0.1651)
		)
		(pad "GND85" thru_hole circle
			(at 43.200066 2.500122 270)
			(size 0.762 0.762)
			(drill 0.359918)
			(layers "*.Cu" "*.Mask")
			(remove_unused_layers no)
			(net "GND")
			(clearance 0.1651)
			(thermal_gap 0.1651)
		)
		(pad "GND86" thru_hole circle
			(at 43.200066 6.100064 270)
			(size 0.762 0.762)
			(drill 0.359918)
			(layers "*.Cu" "*.Mask")
			(remove_unused_layers no)
			(net "GND")
			(clearance 0.1651)
			(thermal_gap 0.1651)
		)
		(pad "GND87" thru_hole circle
			(at 43.200066 9.700006 270)
			(size 0.762 0.762)
			(drill 0.359918)
			(layers "*.Cu" "*.Mask")
			(remove_unused_layers no)
			(net "GND")
			(clearance 0.1651)
			(thermal_gap 0.1651)
		)
		(pad "GND88" thru_hole circle
			(at 44.99991 -0.100076 270)
			(size 0.762 0.762)
			(drill 0.359918)
			(layers "*.Cu" "*.Mask")
			(remove_unused_layers no)
			(net "GND")
			(clearance 0.1651)
			(thermal_gap 0.1651)
		)
		(pad "GND89" thru_hole circle
			(at 44.99991 3.50012 270)
			(size 0.762 0.762)
			(drill 0.359918)
			(layers "*.Cu" "*.Mask")
			(remove_unused_layers no)
			(net "GND")
			(clearance 0.1651)
			(thermal_gap 0.1651)
		)
		(pad "GND90" thru_hole circle
			(at 44.99991 7.100062 270)
			(size 0.762 0.762)
			(drill 0.359918)
			(layers "*.Cu" "*.Mask")
			(remove_unused_layers no)
			(net "GND")
			(clearance 0.1651)
			(thermal_gap 0.1651)
		)
		(pad "GND91" thru_hole circle
			(at 44.99991 10.700004 270)
			(size 0.762 0.762)
			(drill 0.359918)
			(layers "*.Cu" "*.Mask")
			(remove_unused_layers no)
			(net "GND")
			(clearance 0.1651)
			(thermal_gap 0.1651)
		)
		(pad "GND92" thru_hole circle
			(at 46.800008 2.500122 270)
			(size 0.762 0.762)
			(drill 0.359918)
			(layers "*.Cu" "*.Mask")
			(remove_unused_layers no)
			(net "GND")
			(clearance 0.1651)
			(thermal_gap 0.1651)
		)
		(pad "GND93" thru_hole circle
			(at 46.800008 6.100064 270)
			(size 0.762 0.762)
			(drill 0.359918)
			(layers "*.Cu" "*.Mask")
			(remove_unused_layers no)
			(net "GND")
			(clearance 0.1651)
			(thermal_gap 0.1651)
		)
		(pad "GND94" thru_hole circle
			(at 46.800008 9.700006 270)
			(size 0.762 0.762)
			(drill 0.359918)
			(layers "*.Cu" "*.Mask")
			(remove_unused_layers no)
			(net "GND")
			(clearance 0.1651)
			(thermal_gap 0.1651)
		)
		(pad "GND95" thru_hole circle
			(at 48.600106 -0.100076 270)
			(size 0.762 0.762)
			(drill 0.359918)
			(layers "*.Cu" "*.Mask")
			(remove_unused_layers no)
			(net "GND")
			(clearance 0.1651)
			(thermal_gap 0.1651)
		)
		(pad "GND96" thru_hole circle
			(at 48.600106 3.50012 270)
			(size 0.762 0.762)
			(drill 0.359918)
			(layers "*.Cu" "*.Mask")
			(remove_unused_layers no)
			(net "GND")
			(clearance 0.1651)
			(thermal_gap 0.1651)
		)
		(pad "GND97" thru_hole circle
			(at 48.600106 7.100062 270)
			(size 0.762 0.762)
			(drill 0.359918)
			(layers "*.Cu" "*.Mask")
			(remove_unused_layers no)
			(net "GND")
			(clearance 0.1651)
			(thermal_gap 0.1651)
		)
		(pad "GND98" thru_hole circle
			(at 48.600106 10.700004 270)
			(size 0.762 0.762)
			(drill 0.359918)
			(layers "*.Cu" "*.Mask")
			(remove_unused_layers no)
			(net "GND")
			(clearance 0.1651)
			(thermal_gap 0.1651)
		)
		(pad "GND99" thru_hole circle
			(at 50.39995 2.500122 270)
			(size 0.762 0.762)
			(drill 0.359918)
			(layers "*.Cu" "*.Mask")
			(remove_unused_layers no)
			(net "GND")
			(clearance 0.1651)
			(thermal_gap 0.1651)
		)
		(pad "GND100" thru_hole circle
			(at 50.39995 6.100064 270)
			(size 0.762 0.762)
			(drill 0.359918)
			(layers "*.Cu" "*.Mask")
			(remove_unused_layers no)
			(net "GND")
			(clearance 0.1651)
			(thermal_gap 0.1651)
		)
		(pad "GND101" thru_hole circle
			(at 50.39995 9.700006 270)
			(size 0.762 0.762)
			(drill 0.359918)
			(layers "*.Cu" "*.Mask")
			(remove_unused_layers no)
			(net "GND")
			(clearance 0.1651)
			(thermal_gap 0.1651)
		)
		(pad "GND102" thru_hole circle
			(at 52.200048 -0.100076 270)
			(size 0.762 0.762)
			(drill 0.359918)
			(layers "*.Cu" "*.Mask")
			(remove_unused_layers no)
			(net "GND")
			(clearance 0.1651)
			(thermal_gap 0.1651)
		)
		(pad "GND103" thru_hole circle
			(at 52.200048 3.50012 270)
			(size 0.762 0.762)
			(drill 0.359918)
			(layers "*.Cu" "*.Mask")
			(remove_unused_layers no)
			(net "GND")
			(clearance 0.1651)
			(thermal_gap 0.1651)
		)
		(pad "GND104" thru_hole circle
			(at 52.200048 7.100062 270)
			(size 0.762 0.762)
			(drill 0.359918)
			(layers "*.Cu" "*.Mask")
			(remove_unused_layers no)
			(net "GND")
			(clearance 0.1651)
			(thermal_gap 0.1651)
		)
		(pad "GND105" thru_hole circle
			(at 52.200048 10.700004 270)
			(size 0.762 0.762)
			(drill 0.359918)
			(layers "*.Cu" "*.Mask")
			(remove_unused_layers no)
			(net "GND")
			(clearance 0.1651)
			(thermal_gap 0.1651)
		)
		(pad "GND106" thru_hole circle
			(at 53.999892 2.500122 270)
			(size 0.762 0.762)
			(drill 0.359918)
			(layers "*.Cu" "*.Mask")
			(remove_unused_layers no)
			(net "GND")
			(clearance 0.1651)
			(thermal_gap 0.1651)
		)
		(pad "GND107" thru_hole circle
			(at 53.999892 6.100064 270)
			(size 0.762 0.762)
			(drill 0.359918)
			(layers "*.Cu" "*.Mask")
			(remove_unused_layers no)
			(net "GND")
			(clearance 0.1651)
			(thermal_gap 0.1651)
		)
		(pad "GND108" thru_hole circle
			(at 53.999892 9.700006 270)
			(size 0.762 0.762)
			(drill 0.359918)
			(layers "*.Cu" "*.Mask")
			(remove_unused_layers no)
			(net "GND")
			(clearance 0.1651)
			(thermal_gap 0.1651)
		)
		(pad "GND109" thru_hole circle
			(at 55.79999 -0.100076 270)
			(size 0.762 0.762)
			(drill 0.359918)
			(layers "*.Cu" "*.Mask")
			(remove_unused_layers no)
			(net "GND")
			(clearance 0.1651)
			(thermal_gap 0.1651)
		)
		(pad "GND110" thru_hole circle
			(at 55.79999 3.50012 270)
			(size 0.762 0.762)
			(drill 0.359918)
			(layers "*.Cu" "*.Mask")
			(remove_unused_layers no)
			(net "GND")
			(clearance 0.1651)
			(thermal_gap 0.1651)
		)
		(pad "GND111" thru_hole circle
			(at 55.79999 7.100062 270)
			(size 0.762 0.762)
			(drill 0.359918)
			(layers "*.Cu" "*.Mask")
			(remove_unused_layers no)
			(net "GND")
			(clearance 0.1651)
			(thermal_gap 0.1651)
		)
		(pad "GND112" thru_hole circle
			(at 55.79999 10.700004 270)
			(size 0.762 0.762)
			(drill 0.359918)
			(layers "*.Cu" "*.Mask")
			(remove_unused_layers no)
			(net "GND")
			(clearance 0.1651)
			(thermal_gap 0.1651)
		)
		(pad "GND113" thru_hole circle
			(at 57.600088 2.500122 270)
			(size 0.762 0.762)
			(drill 0.359918)
			(layers "*.Cu" "*.Mask")
			(remove_unused_layers no)
			(net "GND")
			(clearance 0.1651)
			(thermal_gap 0.1651)
		)
		(pad "GND114" thru_hole circle
			(at 57.600088 6.100064 270)
			(size 0.762 0.762)
			(drill 0.359918)
			(layers "*.Cu" "*.Mask")
			(remove_unused_layers no)
			(net "GND")
			(clearance 0.1651)
			(thermal_gap 0.1651)
		)
		(pad "GND115" thru_hole circle
			(at 57.600088 9.700006 270)
			(size 0.762 0.762)
			(drill 0.359918)
			(layers "*.Cu" "*.Mask")
			(remove_unused_layers no)
			(net "GND")
			(clearance 0.1651)
			(thermal_gap 0.1651)
		)
		(pad "GND116" thru_hole circle
			(at 59.399932 -0.100076 270)
			(size 0.762 0.762)
			(drill 0.359918)
			(layers "*.Cu" "*.Mask")
			(remove_unused_layers no)
			(net "GND")
			(clearance 0.1651)
			(thermal_gap 0.1651)
		)
		(pad "GND117" thru_hole circle
			(at 59.399932 3.50012 270)
			(size 0.762 0.762)
			(drill 0.359918)
			(layers "*.Cu" "*.Mask")
			(remove_unused_layers no)
			(net "GND")
			(clearance 0.1651)
			(thermal_gap 0.1651)
		)
		(pad "GND118" thru_hole circle
			(at 59.399932 7.100062 270)
			(size 0.762 0.762)
			(drill 0.359918)
			(layers "*.Cu" "*.Mask")
			(remove_unused_layers no)
			(net "GND")
			(clearance 0.1651)
			(thermal_gap 0.1651)
		)
		(pad "GND119" thru_hole circle
			(at 59.399932 10.700004 270)
			(size 0.762 0.762)
			(drill 0.359918)
			(layers "*.Cu" "*.Mask")
			(remove_unused_layers no)
			(net "GND")
			(clearance 0.1651)
			(thermal_gap 0.1651)
		)
		(pad "GND120" thru_hole circle
			(at 61.20003 2.500122 270)
			(size 0.762 0.762)
			(drill 0.359918)
			(layers "*.Cu" "*.Mask")
			(remove_unused_layers no)
			(net "GND")
			(clearance 0.1651)
			(thermal_gap 0.1651)
		)
		(pad "GND121" thru_hole circle
			(at 61.20003 6.100064 270)
			(size 0.762 0.762)
			(drill 0.359918)
			(layers "*.Cu" "*.Mask")
			(remove_unused_layers no)
			(net "GND")
			(clearance 0.1651)
			(thermal_gap 0.1651)
		)
		(pad "GND122" thru_hole circle
			(at 61.20003 9.700006 270)
			(size 0.762 0.762)
			(drill 0.359918)
			(layers "*.Cu" "*.Mask")
			(remove_unused_layers no)
			(net "GND")
			(clearance 0.1651)
			(thermal_gap 0.1651)
		)
		(pad "GND123" thru_hole circle
			(at 62.999874 -0.100076 270)
			(size 0.762 0.762)
			(drill 0.359918)
			(layers "*.Cu" "*.Mask")
			(remove_unused_layers no)
			(net "GND")
			(clearance 0.1651)
			(thermal_gap 0.1651)
		)
		(pad "GND124" thru_hole circle
			(at 62.999874 3.50012 270)
			(size 0.762 0.762)
			(drill 0.359918)
			(layers "*.Cu" "*.Mask")
			(remove_unused_layers no)
			(net "GND")
			(clearance 0.1651)
			(thermal_gap 0.1651)
		)
		(pad "GND125" thru_hole circle
			(at 62.999874 7.100062 270)
			(size 0.762 0.762)
			(drill 0.359918)
			(layers "*.Cu" "*.Mask")
			(remove_unused_layers no)
			(net "GND")
			(clearance 0.1651)
			(thermal_gap 0.1651)
		)
		(pad "GND126" thru_hole circle
			(at 62.999874 10.700004 270)
			(size 0.762 0.762)
			(drill 0.359918)
			(layers "*.Cu" "*.Mask")
			(remove_unused_layers no)
			(net "GND")
			(clearance 0.1651)
			(thermal_gap 0.1651)
		)
	)
)
